# T6G (Grand Teton) — schematic netlist excerpt (pin names and nets, part order shuffled) for the footprints in the layout excerpt that follows; sources: Cadence DE-HDL packaged netlist, KiCad conversion of 04192023_DAF0TMB3IC0_F0TG_MB_C_brd_V02_OCP.brd

C499  Q_CAP  10UF 6.3V 20% X6S  pkg C0402  page 356 : A = P0V9_CPU1_RT3_2A ; B = GND
C142  Q_CAP  10UF 25V 10% X6S  pkg C0805  page 86 : A = P12V_MEM_CPU0 ; B = GND
C6104  Q_CAP  0.1UF 25V 10% X7R  pkg 0402  page 179 : A = P3V3_AUX_CPU0_USB2_AVDD33 ; B = GND

(kicad_pcb
	(version 20260206)
	(generator "pcbnew")
	(generator_version "10.0")
	(general
		(thickness 1.6)
		(legacy_teardrops no)
	)
	(paper "A4")
	(title_block
		(title "04192023_DAF0TMB3IC0_F0TG_MB_C_brd_V02_OCP.brd")
		(comment 1 "Grand Teton / footprints 7676-7678 of 8354")
	)
	(layers
		(0 "F.Cu" signal "TOP")
		(4 "In1.Cu" signal "GND")
		(6 "In2.Cu" signal "IN1")
		(8 "In3.Cu" signal "GND1")
		(10 "In4.Cu" signal "IN2")
		(12 "In5.Cu" signal "GND2")
		(14 "In6.Cu" signal "IN3")
		(16 "In7.Cu" signal "GND3")
		(18 "In8.Cu" signal "VCC")
		(20 "In9.Cu" signal "VCC1")
		(22 "In10.Cu" signal "GND4")
		(24 "In11.Cu" signal "IN4")
		(26 "In12.Cu" signal "GND5")
		(28 "In13.Cu" signal "IN5")
		(30 "In14.Cu" signal "GND6")
		(32 "In15.Cu" signal "IN6")
		(34 "In16.Cu" signal "GND7")
		(2 "B.Cu" signal "BOTTOM")
		(9 "F.Adhes" user "F.Adhesive")
		(11 "B.Adhes" user "B.Adhesive")
		(13 "F.Paste" user "Package Geometry/Pastemask Top")
		(15 "B.Paste" user "Package Geometry/Pastemask Bottom")
		(5 "F.SilkS" user "Ref Des/Silkscreen Top")
		(7 "B.SilkS" user "Ref Des/Silkscreen Bottom")
		(1 "F.Mask" user "Board Geometry/Soldermask Top")
		(3 "B.Mask" user "Board Geometry/Soldermask Bottom")
		(17 "Dwgs.User" user "User.Drawings")
		(19 "Cmts.User" user "User.Comments")
		(21 "Eco1.User" user "User.Eco1")
		(23 "Eco2.User" user "User.Eco2")
		(25 "Edge.Cuts" user "Board Geometry/Outline")
		(27 "Margin" user)
		(31 "F.CrtYd" user "Package Geometry/Place Bound Top")
		(29 "B.CrtYd" user "Package Geometry/Place Bound Bottom")
		(35 "F.Fab" user "Ref Des/Assembly Top")
		(33 "B.Fab" user "Ref Des/Assembly Bottom")
	)
	(footprint ""
		(layer "B.Cu")
		(at 128.891284 -390.560052 90)
		(property "Reference" "C499"
			(at 0 0 90)
			(layer "B.SilkS")
			(hide yes)
			(effects
				(font
					(size 1.27 1.27)
				)
				(justify mirror)
			)
		)
		(property "Value" ""
			(at 0 0 90)
			(layer "B.Fab")
			(effects
				(font
					(size 1.27 1.27)
				)
				(justify mirror)
			)
		)
		(duplicate_pad_numbers_are_jumpers no)
		(fp_line
			(start 0.7874 -0.4064)
			(end -0.7874 -0.4064)
			(stroke
				(width 0.1524)
				(type default)
			)
			(layer "B.SilkS")
		)
		(fp_line
			(start -0.7874 -0.4064)
			(end -0.7874 0.4064)
			(stroke
				(width 0.1524)
				(type default)
			)
			(layer "B.SilkS")
		)
		(fp_line
			(start 0.7874 0.4064)
			(end 0.7874 -0.4064)
			(stroke
				(width 0.1524)
				(type default)
			)
			(layer "B.SilkS")
		)
		(fp_line
			(start -0.7874 0.4064)
			(end 0.7874 0.4064)
			(stroke
				(width 0.1524)
				(type default)
			)
			(layer "B.SilkS")
		)
		(fp_line
			(start 0.67945 -0.305054)
			(end 0.12065 -0.305054)
			(stroke
				(width 0.1)
				(type default)
			)
			(layer "B.Fab")
		)
		(fp_line
			(start 0.12065 -0.305054)
			(end 0.12065 -0.2794)
			(stroke
				(width 0.1)
				(type default)
			)
			(layer "B.Fab")
		)
		(fp_line
			(start -0.12065 -0.3048)
			(end -0.67945 -0.3048)
			(stroke
				(width 0.1)
				(type default)
			)
			(layer "B.Fab")
		)
		(fp_line
			(start -0.67945 -0.3048)
			(end -0.67945 0.3048)
			(stroke
				(width 0.1)
				(type default)
			)
			(layer "B.Fab")
		)
		(fp_line
			(start 0.12065 -0.2794)
			(end -0.12065 -0.2794)
			(stroke
				(width 0.1)
				(type default)
			)
			(layer "B.Fab")
		)
		(fp_line
			(start -0.12065 -0.2794)
			(end -0.12065 -0.3048)
			(stroke
				(width 0.1)
				(type default)
			)
			(layer "B.Fab")
		)
		(fp_line
			(start 0.12065 0.2794)
			(end 0.12065 0.3048)
			(stroke
				(width 0.1)
				(type default)
			)
			(layer "B.Fab")
		)
		(fp_line
			(start -0.120396 0.2794)
			(end 0.12065 0.2794)
			(stroke
				(width 0.1)
				(type default)
			)
			(layer "B.Fab")
		)
		(fp_line
			(start 0.67945 0.3048)
			(end 0.67945 -0.305054)
			(stroke
				(width 0.1)
				(type default)
			)
			(layer "B.Fab")
		)
		(fp_line
			(start 0.12065 0.3048)
			(end 0.67945 0.3048)
			(stroke
				(width 0.1)
				(type default)
			)
			(layer "B.Fab")
		)
		(fp_line
			(start -0.120396 0.3048)
			(end -0.120396 0.2794)
			(stroke
				(width 0.1)
				(type default)
			)
			(layer "B.Fab")
		)
		(fp_line
			(start -0.67945 0.3048)
			(end -0.120396 0.3048)
			(stroke
				(width 0.1)
				(type default)
			)
			(layer "B.Fab")
		)
		(pad "1" smd circle
			(at 0.40005 0 270)
			(size 0 0)
			(layers "B.Cu" "B.Mask" "B.Paste")
			(net "P0V9_CPU1_RT3_2A")
		)
		(pad "2" smd circle
			(at -0.40005 0 270)
			(size 0 0)
			(layers "B.Cu" "B.Mask" "B.Paste")
			(net "GND")
		)
	)
	(footprint ""
		(layer "B.Cu")
		(at 110.039404 -28.70327 -90)
		(property "Reference" "C6104"
			(at 0 0 90)
			(layer "B.SilkS")
			(hide yes)
			(effects
				(font
					(size 1.27 1.27)
				)
				(justify mirror)
			)
		)
		(property "Value" ""
			(at 0 0 90)
			(layer "B.Fab")
			(effects
				(font
					(size 1.27 1.27)
				)
				(justify mirror)
			)
		)
		(duplicate_pad_numbers_are_jumpers no)
		(fp_line
			(start -0.7874 0.4064)
			(end 0.7874 0.4064)
			(stroke
				(width 0.1524)
				(type default)
			)
			(layer "B.SilkS")
		)
		(fp_line
			(start 0.7874 0.4064)
			(end 0.7874 -0.4064)
			(stroke
				(width 0.1524)
				(type default)
			)
			(layer "B.SilkS")
		)
		(fp_line
			(start -0.7874 -0.4064)
			(end -0.7874 0.4064)
			(stroke
				(width 0.1524)
				(type default)
			)
			(layer "B.SilkS")
		)
		(fp_line
			(start 0.7874 -0.4064)
			(end -0.7874 -0.4064)
			(stroke
				(width 0.1524)
				(type default)
			)
			(layer "B.SilkS")
		)
		(fp_line
			(start -0.67945 0.3048)
			(end -0.120396 0.3048)
			(stroke
				(width 0.1)
				(type default)
			)
			(layer "B.Fab")
		)
		(fp_line
			(start -0.120396 0.3048)
			(end -0.120396 0.2794)
			(stroke
				(width 0.1)
				(type default)
			)
			(layer "B.Fab")
		)
		(fp_line
			(start 0.12065 0.3048)
			(end 0.67945 0.3048)
			(stroke
				(width 0.1)
				(type default)
			)
			(layer "B.Fab")
		)
		(fp_line
			(start 0.67945 0.3048)
			(end 0.67945 -0.305054)
			(stroke
				(width 0.1)
				(type default)
			)
			(layer "B.Fab")
		)
		(fp_line
			(start -0.120396 0.2794)
			(end 0.12065 0.2794)
			(stroke
				(width 0.1)
				(type default)
			)
			(layer "B.Fab")
		)
		(fp_line
			(start 0.12065 0.2794)
			(end 0.12065 0.3048)
			(stroke
				(width 0.1)
				(type default)
			)
			(layer "B.Fab")
		)
		(fp_line
			(start -0.12065 -0.2794)
			(end -0.12065 -0.3048)
			(stroke
				(width 0.1)
				(type default)
			)
			(layer "B.Fab")
		)
		(fp_line
			(start 0.12065 -0.2794)
			(end -0.12065 -0.2794)
			(stroke
				(width 0.1)
				(type default)
			)
			(layer "B.Fab")
		)
		(fp_line
			(start -0.67945 -0.3048)
			(end -0.67945 0.3048)
			(stroke
				(width 0.1)
				(type default)
			)
			(layer "B.Fab")
		)
		(fp_line
			(start -0.12065 -0.3048)
			(end -0.67945 -0.3048)
			(stroke
				(width 0.1)
				(type default)
			)
			(layer "B.Fab")
		)
		(fp_line
			(start 0.12065 -0.305054)
			(end 0.12065 -0.2794)
			(stroke
				(width 0.1)
				(type default)
			)
			(layer "B.Fab")
		)
		(fp_line
			(start 0.67945 -0.305054)
			(end 0.12065 -0.305054)
			(stroke
				(width 0.1)
				(type default)
			)
			(layer "B.Fab")
		)
		(pad "1" smd circle
			(at 0.40005 0 90)
			(size 0 0)
			(layers "B.Cu" "B.Mask" "B.Paste")
			(net "P3V3_AUX_CPU0_USB2_AVDD33")
		)
		(pad "2" smd circle
			(at -0.40005 0 90)
			(size 0 0)
			(layers "B.Cu" "B.Mask" "B.Paste")
			(net "GND")
		)
	)
	(footprint ""
		(layer "B.Cu")
		(at 303.268126 -192.660016 180)
		(property "Reference" "C142"
			(at 0 0 0)
			(layer "B.SilkS")
			(hide yes)
			(effects
				(font
					(size 1.27 1.27)
				)
				(justify mirror)
			)
		)
		(property "Value" ""
			(at 0 0 0)
			(layer "B.Fab")
			(effects
				(font
					(size 1.27 1.27)
				)
				(justify mirror)
			)
		)
		(duplicate_pad_numbers_are_jumpers no)
		(fp_line
			(start 1.524 0.762)
			(end 1.524 -0.762)
			(stroke
				(width 0.1524)
				(type default)
			)
			(layer "B.SilkS")
		)
		(fp_line
			(start 1.524 -0.762)
			(end -1.524 -0.762)
			(stroke
				(width 0.1524)
				(type default)
			)
			(layer "B.SilkS")
		)
		(fp_line
			(start -1.524 0.762)
			(end 1.524 0.762)
			(stroke
				(width 0.1524)
				(type default)
			)
			(layer "B.SilkS")
		)
		(fp_line
			(start -1.524 -0.762)
			(end -1.524 0.762)
			(stroke
				(width 0.1524)
				(type default)
			)
			(layer "B.SilkS")
		)
		(fp_line
			(start 1.1049 0.724916)
			(end -1.1049 0.724916)
			(stroke
				(width 0.1)
				(type default)
			)
			(layer "B.Fab")
		)
		(fp_line
			(start 1.1049 -0.724916)
			(end 1.1049 0.724916)
			(stroke
				(width 0.1)
				(type default)
			)
			(layer "B.Fab")
		)
		(fp_line
			(start -1.1049 0.724916)
			(end -1.1049 -0.724916)
			(stroke
				(width 0.1)
				(type default)
			)
			(layer "B.Fab")
		)
		(fp_line
			(start -1.1049 -0.724916)
			(end 1.1049 -0.724916)
			(stroke
				(width 0.1)
				(type default)
			)
			(layer "B.Fab")
		)
		(pad "1" smd rect
			(at 0.889 0 180)
			(size 1.016 1.27)
			(layers "B.Cu" "B.Mask" "B.Paste")
			(net "P12V_MEM_CPU0")
		)
		(pad "2" smd rect
			(at -0.889 0 180)
			(size 1.016 1.27)
			(layers "B.Cu" "B.Mask" "B.Paste")
			(net "GND")
		)
	)
)
